FILE_TYPE = MACRO_DRAWING;
SET COLOR_WIRE YELLOW;
SET COLOR_PROP ORANGE;
SET COLOR_DOT WHITE;
SET COLOR_ARC YELLOW;
SET COLOR_BODY GREEN;
SET COLOR_NOTE PURPLE;
SET PROP_DISPLAY VALUE;
SET PAGE_NUMBER P1;
FORCEADD SYNONYM..1
(1850 2050);
PAINT MONO (1850 2050);
FORCEPROP 2 LAST PATH 4P
J 0
(1850 2150);
DISPLAY 0.872340 (1850 2150);
PAINT YELLOW (1850 2150);
FORCEPROP 1 LAST NEEDS_NO_SIZE TRUE
J 0
(1875 2125);
DISPLAY 0.872340 (1875 2125);
PAINT MONO (1875 2125);
DISPLAY INVISIBLE (1875 2125);
FORCEPROP 1 LAST BODY_TYPE PLUMBING
J 0
(1850 2100);
DISPLAY 0.872340 (1850 2100);
PAINT GREEN (1850 2100);
DISPLAY INVISIBLE (1850 2100);
FORCEPROP 2 LAST CDS_LIB mstr_standard
J 0
(1850 2050);
DISPLAY 0.851064 (1850 2050);
DISPLAY INVISIBLE (1850 2050);
FORCEADD DRAWING..2
(1275 1750);
PAINT MONO (1275 1750);
FORCEPROP 1 LAST LAST_MODIFIED Tue Oct 25 14:30:26 2011
J 0
(1575 1500);
DISPLAY 0.872340 (1575 1500);
PAINT GREEN (1575 1500);
FORCEPROP 1 LAST TITLE P5V
J 0
(1325 1700);
DISPLAY 0.872340 (1325 1700);
PAINT GREEN (1325 1700);
FORCEPROP 1 LAST ABBREV P5V
J 0
(1325 1650);
DISPLAY 0.872340 (1325 1650);
PAINT GREEN (1325 1650);
WIRE 16 -1 (1800 2050)(1200 2050);
FORCEPROP 2 LAST SIG_NAME G\I
J 0
(1025 2060);
DISPLAY 0.872340 (1025 2060);
PAINT MONO (1025 2060);
WIRE 0 -1 (1900 2050)(2050 2050);
FORCEPROP 2 LAST SIG_NAME P5V \G
J 0
(2075 2085);
DISPLAY 0.872340 (2075 2085);
PAINT MONO (2075 2085);
QUIT
